# SCM (Grand Teton) — schematic netlist excerpt (pin names and nets, part order shuffled) for the footprints in the layout excerpt that follows; sources: Cadence DE-HDL packaged netlist, KiCad conversion of 12092022_DA0F0TMDCD0_F0T_Management_Board_D_brd_V3_OCP.brd

R625  Q_RES  4.7K 1% CHIP  pkg 0402LF  page 34 : A = P3V3_AUX ; B = RST_RSMRST_N
R211  Q_RES  10K 1% CHIP  pkg 0402LF  page 15 : A = P3V3_RGM ; B = FM_BMC_SSPRST_N

(kicad_pcb
	(version 20260206)
	(generator "pcbnew")
	(generator_version "10.0")
	(general
		(thickness 1.6)
		(legacy_teardrops no)
	)
	(paper "A4")
	(title_block
		(title "12092022_DA0F0TMDCD0_F0T_Management_Board_D_brd_V3_OCP.brd")
		(comment 1 "Grand Teton / footprints 1092-1093 of 1440")
	)
	(layers
		(0 "F.Cu" signal "TOP")
		(4 "In1.Cu" signal "GND")
		(6 "In2.Cu" signal "IN1")
		(8 "In3.Cu" signal "GND1")
		(10 "In4.Cu" signal "IN2")
		(12 "In5.Cu" signal "VCC")
		(14 "In6.Cu" signal "VCC1")
		(16 "In7.Cu" signal "IN3")
		(18 "In8.Cu" signal "GND2")
		(20 "In9.Cu" signal "IN4")
		(22 "In10.Cu" signal "GND3")
		(2 "B.Cu" signal "BOTTOM")
		(9 "F.Adhes" user "F.Adhesive")
		(11 "B.Adhes" user "B.Adhesive")
		(13 "F.Paste" user "Package Geometry/Pastemask Top")
		(15 "B.Paste" user "Package Geometry/Pastemask Bottom")
		(5 "F.SilkS" user "Ref Des/Silkscreen Top")
		(7 "B.SilkS" user "Ref Des/Silkscreen Bottom")
		(1 "F.Mask" user "Board Geometry/Soldermask Top")
		(3 "B.Mask" user "Board Geometry/Soldermask Bottom")
		(17 "Dwgs.User" user "User.Drawings")
		(19 "Cmts.User" user "User.Comments")
		(21 "Eco1.User" user "User.Eco1")
		(23 "Eco2.User" user "User.Eco2")
		(25 "Edge.Cuts" user "Board Geometry/Outline")
		(27 "Margin" user)
		(31 "F.CrtYd" user "Package Geometry/Place Bound Top")
		(29 "B.CrtYd" user "Package Geometry/Place Bound Bottom")
		(35 "F.Fab" user "Ref Des/Assembly Top")
		(33 "B.Fab" user "Ref Des/Assembly Bottom")
	)
	(footprint ""
		(layer "B.Cu")
		(at 26.8224 -84.3788 -90)
		(property "Reference" "R625"
			(at 0 0 90)
			(layer "B.SilkS")
			(hide yes)
			(effects
				(font
					(size 1.27 1.27)
				)
				(justify mirror)
			)
		)
		(property "Value" ""
			(at 0 0 90)
			(layer "B.Fab")
			(effects
				(font
					(size 1.27 1.27)
				)
				(justify mirror)
			)
		)
		(duplicate_pad_numbers_are_jumpers no)
		(fp_line
			(start -0.7874 0.4064)
			(end 0.7874 0.4064)
			(stroke
				(width 0.1524)
				(type default)
			)
			(layer "B.SilkS")
		)
		(fp_line
			(start 0.7874 0.4064)
			(end 0.7874 -0.4064)
			(stroke
				(width 0.1524)
				(type default)
			)
			(layer "B.SilkS")
		)
		(fp_line
			(start -0.7874 -0.4064)
			(end -0.7874 0.4064)
			(stroke
				(width 0.1524)
				(type default)
			)
			(layer "B.SilkS")
		)
		(fp_line
			(start 0.7874 -0.4064)
			(end -0.7874 -0.4064)
			(stroke
				(width 0.1524)
				(type default)
			)
			(layer "B.SilkS")
		)
		(fp_line
			(start -0.67945 0.3048)
			(end -0.120396 0.3048)
			(stroke
				(width 0.1)
				(type default)
			)
			(layer "B.Fab")
		)
		(fp_line
			(start -0.120396 0.3048)
			(end -0.120396 0.2794)
			(stroke
				(width 0.1)
				(type default)
			)
			(layer "B.Fab")
		)
		(fp_line
			(start 0.12065 0.3048)
			(end 0.67945 0.3048)
			(stroke
				(width 0.1)
				(type default)
			)
			(layer "B.Fab")
		)
		(fp_line
			(start 0.67945 0.3048)
			(end 0.67945 -0.305054)
			(stroke
				(width 0.1)
				(type default)
			)
			(layer "B.Fab")
		)
		(fp_line
			(start -0.120396 0.2794)
			(end 0.12065 0.2794)
			(stroke
				(width 0.1)
				(type default)
			)
			(layer "B.Fab")
		)
		(fp_line
			(start 0.12065 0.2794)
			(end 0.12065 0.3048)
			(stroke
				(width 0.1)
				(type default)
			)
			(layer "B.Fab")
		)
		(fp_line
			(start -0.12065 -0.2794)
			(end -0.12065 -0.3048)
			(stroke
				(width 0.1)
				(type default)
			)
			(layer "B.Fab")
		)
		(fp_line
			(start 0.12065 -0.2794)
			(end -0.12065 -0.2794)
			(stroke
				(width 0.1)
				(type default)
			)
			(layer "B.Fab")
		)
		(fp_line
			(start -0.67945 -0.3048)
			(end -0.67945 0.3048)
			(stroke
				(width 0.1)
				(type default)
			)
			(layer "B.Fab")
		)
		(fp_line
			(start -0.12065 -0.3048)
			(end -0.67945 -0.3048)
			(stroke
				(width 0.1)
				(type default)
			)
			(layer "B.Fab")
		)
		(fp_line
			(start 0.12065 -0.305054)
			(end 0.12065 -0.2794)
			(stroke
				(width 0.1)
				(type default)
			)
			(layer "B.Fab")
		)
		(fp_line
			(start 0.67945 -0.305054)
			(end 0.12065 -0.305054)
			(stroke
				(width 0.1)
				(type default)
			)
			(layer "B.Fab")
		)
		(pad "1" smd circle
			(at 0.40005 0 90)
			(size 0 0)
			(layers "B.Cu" "B.Mask" "B.Paste")
			(net "P3V3_AUX")
		)
		(pad "2" smd circle
			(at -0.40005 0 90)
			(size 0 0)
			(layers "B.Cu" "B.Mask" "B.Paste")
			(net "RST_RSMRST_N")
		)
	)
	(footprint ""
		(layer "B.Cu")
		(at 66.127884 -30.740604 -90)
		(property "Reference" "R211"
			(at 0 0 90)
			(layer "B.SilkS")
			(hide yes)
			(effects
				(font
					(size 1.27 1.27)
				)
				(justify mirror)
			)
		)
		(property "Value" ""
			(at 0 0 90)
			(layer "B.Fab")
			(effects
				(font
					(size 1.27 1.27)
				)
				(justify mirror)
			)
		)
		(duplicate_pad_numbers_are_jumpers no)
		(fp_line
			(start -0.7874 0.4064)
			(end 0.7874 0.4064)
			(stroke
				(width 0.1524)
				(type default)
			)
			(layer "B.SilkS")
		)
		(fp_line
			(start 0.7874 0.4064)
			(end 0.7874 -0.4064)
			(stroke
				(width 0.1524)
				(type default)
			)
			(layer "B.SilkS")
		)
		(fp_line
			(start -0.7874 -0.4064)
			(end -0.7874 0.4064)
			(stroke
				(width 0.1524)
				(type default)
			)
			(layer "B.SilkS")
		)
		(fp_line
			(start 0.7874 -0.4064)
			(end -0.7874 -0.4064)
			(stroke
				(width 0.1524)
				(type default)
			)
			(layer "B.SilkS")
		)
		(fp_line
			(start -0.67945 0.3048)
			(end -0.120396 0.3048)
			(stroke
				(width 0.1)
				(type default)
			)
			(layer "B.Fab")
		)
		(fp_line
			(start -0.120396 0.3048)
			(end -0.120396 0.2794)
			(stroke
				(width 0.1)
				(type default)
			)
			(layer "B.Fab")
		)
		(fp_line
			(start 0.12065 0.3048)
			(end 0.67945 0.3048)
			(stroke
				(width 0.1)
				(type default)
			)
			(layer "B.Fab")
		)
		(fp_line
			(start 0.67945 0.3048)
			(end 0.67945 -0.305054)
			(stroke
				(width 0.1)
				(type default)
			)
			(layer "B.Fab")
		)
		(fp_line
			(start -0.120396 0.2794)
			(end 0.12065 0.2794)
			(stroke
				(width 0.1)
				(type default)
			)
			(layer "B.Fab")
		)
		(fp_line
			(start 0.12065 0.2794)
			(end 0.12065 0.3048)
			(stroke
				(width 0.1)
				(type default)
			)
			(layer "B.Fab")
		)
		(fp_line
			(start -0.12065 -0.2794)
			(end -0.12065 -0.3048)
			(stroke
				(width 0.1)
				(type default)
			)
			(layer "B.Fab")
		)
		(fp_line
			(start 0.12065 -0.2794)
			(end -0.12065 -0.2794)
			(stroke
				(width 0.1)
				(type default)
			)
			(layer "B.Fab")
		)
		(fp_line
			(start -0.67945 -0.3048)
			(end -0.67945 0.3048)
			(stroke
				(width 0.1)
				(type default)
			)
			(layer "B.Fab")
		)
		(fp_line
			(start -0.12065 -0.3048)
			(end -0.67945 -0.3048)
			(stroke
				(width 0.1)
				(type default)
			)
			(layer "B.Fab")
		)
		(fp_line
			(start 0.12065 -0.305054)
			(end 0.12065 -0.2794)
			(stroke
				(width 0.1)
				(type default)
			)
			(layer "B.Fab")
		)
		(fp_line
			(start 0.67945 -0.305054)
			(end 0.12065 -0.305054)
			(stroke
				(width 0.1)
				(type default)
			)
			(layer "B.Fab")
		)
		(pad "1" smd circle
			(at 0.40005 0 90)
			(size 0 0)
			(layers "B.Cu" "B.Mask" "B.Paste")
			(net "P3V3_RGM")
		)
		(pad "2" smd circle
			(at -0.40005 0 90)
			(size 0 0)
			(layers "B.Cu" "B.Mask" "B.Paste")
			(net "FM_BMC_SSPRST_N")
		)
	)
)
